# T6G (Grand Teton) — schematic netlist excerpt (pin names and nets, part order shuffled) for the footprints in the layout excerpt that follows; sources: Cadence DE-HDL packaged netlist, KiCad conversion of 04192023_DAF0TMB3IC0_F0TG_MB_C_brd_V02_OCP.brd

J38  SCONN168_ME1016810202011  IO  pkg CON_F168S2H7D_P0-6W2-95_LUH  page 131
  GND_A1  = GND
  GND_A2  = GND
  GND_A3  = GND
  GND_A4  = GND
  GND_A5  = GND
  GND_A6  = GND
  SMCLK  = SMB_OCP_SFF_3V3AUX_BUF_R_SCL
  SMDAT  = SMB_OCP_SFF_3V3AUX_BUF_R_SDA
  \smrst#\  = RST_SMB_OCP_SFF_N
  \prsnta#\  = OCP_SFF_PRSNTA_R_N
  \perst1#\  = RST_PERST1_OCP_SFF_N
  \prsntb2#\  = OCP_SFF_PRSNT2_R_N
  GND_A13  = GND
  REFCLKN1  = CLK_100M_CPU0_CLK03_DN
  REFCLKP1  = CLK_100M_CPU0_CLK03_DP
  GND_A16  = GND
  PERN0  = P5E_CPU0_G3_RX_DN<0>
  PERP0  = P5E_CPU0_G3_RX_DP<0>
  GND_A19  = GND
  PERN1  = P5E_CPU0_G3_RX_DN<1>
  PERP1  = P5E_CPU0_G3_RX_DP<1>
  GND_A22  = GND
  PERN2  = P5E_CPU0_G3_RX_DN<2>
  PERP2  = P5E_CPU0_G3_RX_DP<2>
  GND_A25  = GND
  PERN3  = P5E_CPU0_G3_RX_DN<3>
  PERP3  = P5E_CPU0_G3_RX_DP<3>
  GND_A28  = GND
  GND_A29  = GND
  PERN4  = P5E_CPU0_G3_RX_DN<4>
  PERP4  = P5E_CPU0_G3_RX_DP<4>
  GND_A32  = GND
  PERN5  = P5E_CPU0_G3_RX_DN<5>
  PERP5  = P5E_CPU0_G3_RX_DP<5>
  GND_A35  = GND
  PERN6  = P5E_CPU0_G3_RX_DN<6>
  PERP6  = P5E_CPU0_G3_RX_DP<6>
  GND_A38  = GND
  PERN7  = P5E_CPU0_G3_RX_DN<7>
  PERP7  = P5E_CPU0_G3_RX_DP<7>
  GND_A41  = GND
  \prsntb1#\  = OCP_SFF_PRSNT1_R_N
  GND_A43  = GND
  PERN8  = P5E_CPU0_G3_RX_DN<8>
  PERP8  = P5E_CPU0_G3_RX_DP<8>
  GND_A46  = GND
  PERN9  = P5E_CPU0_G3_RX_DN<9>
  PERP9  = P5E_CPU0_G3_RX_DP<9>
  GND_A49  = GND
  PERN10  = P5E_CPU0_G3_RX_DN<10>
  PERP10  = P5E_CPU0_G3_RX_DP<10>
  GND_A52  = GND
  PERN11  = P5E_CPU0_G3_RX_DN<11>
  PERP11  = P5E_CPU0_G3_RX_DP<11>
  GND_A55  = GND
  PERN12  = P5E_CPU0_G3_RX_DN<12>
  PERP12  = P5E_CPU0_G3_RX_DP<12>
  GND_A58  = GND
  PERN13  = P5E_CPU0_G3_RX_DN<13>
  PERP13  = P5E_CPU0_G3_RX_DP<13>
  GND_A61  = GND
  PERN14  = P5E_CPU0_G3_RX_DN<14>
  PERP14  = P5E_CPU0_G3_RX_DP<14>
  GND_A64  = GND
  PERN15  = P5E_CPU0_G3_RX_DN<15>
  PERP15  = P5E_CPU0_G3_RX_DP<15>
  GND_A67  = GND
  USB_DATN  = USB2_P11_DN
  USB_DATP  = USB2_P11_DP
  \pwrbrk0#\  = OCP_SFF_PWRBRK_N
  \+12v_edge_b1\  = P12V_OCP_SFF_R
  \+12v_edge_b2\  = P12V_OCP_SFF_R
  \+12v_edge_b3\  = P12V_OCP_SFF_R
  \+12v_edge_b4\  = P12V_OCP_SFF_R
  \+12v_edge_b5\  = P12V_OCP_SFF_R
  \+12v_edge_b6\  = P12V_OCP_SFF_R
  \bif0#\  = OCP_SFF_BIF0_R_N
  \bif1#\  = OCP_SFF_BIF1_R_N
  \bif2#\  = OCP_SFF_BIF2_R_N
  \perst0#\  = RST_PERST0_OCP_SFF_N
  \+3.3v_edge\  = P3V3_OCP_SFF
  AUX_PWR_EN  = OCP_SFF_AUX_PWR_EN_R
  GND_B13  = GND
  REFCLKN0  = CLK_100M_CPU0_CLK02_DN
  REFCLKP0  = CLK_100M_CPU0_CLK02_DP
  GND_B16  = GND
  PETN0  = P5E_CPU0_G3_TX_C_DP<0>
  PETP0  = P5E_CPU0_G3_TX_C_DN<0>
  GND_B19  = GND
  PETN1  = P5E_CPU0_G3_TX_C_DP<1>
  PETP1  = P5E_CPU0_G3_TX_C_DN<1>
  GND_B22  = GND
  PETN2  = P5E_CPU0_G3_TX_C_DP<2>
  PETP2  = P5E_CPU0_G3_TX_C_DN<2>
  GND_B25  = GND
  PETN3  = P5E_CPU0_G3_TX_C_DP<3>
  PETP3  = P5E_CPU0_G3_TX_C_DN<3>
  GND_B28  = GND
  GND_B29  = GND
  PETN4  = P5E_CPU0_G3_TX_C_DP<4>
  PETP4  = P5E_CPU0_G3_TX_C_DN<4>
  GND_B32  = GND
  PETN5  = P5E_CPU0_G3_TX_C_DP<5>
  PETP5  = P5E_CPU0_G3_TX_C_DN<5>
  GND_B35  = GND
  PETN6  = P5E_CPU0_G3_TX_C_DP<6>
  PETP6  = P5E_CPU0_G3_TX_C_DN<6>
  GND_B38  = GND
  PETN7  = P5E_CPU0_G3_TX_C_DP<7>
  PETP7  = P5E_CPU0_G3_TX_C_DN<7>
  GND_B41  = GND
  \prsntb0#\  = OCP_SFF_PRSNT0_R_N
  GND_B43  = GND
  PETN8  = P5E_CPU0_G3_TX_C_DP<8>
  PETP8  = P5E_CPU0_G3_TX_C_DN<8>
  GND_B46  = GND
  PETN9  = P5E_CPU0_G3_TX_C_DP<9>
  PETP9  = P5E_CPU0_G3_TX_C_DN<9>
  GND_B49  = GND
  PETN10  = P5E_CPU0_G3_TX_C_DP<10>
  PETP10  = P5E_CPU0_G3_TX_C_DN<10>
  GND_B52  = GND
  PETN11  = P5E_CPU0_G3_TX_C_DP<11>
  PETP11  = P5E_CPU0_G3_TX_C_DN<11>
  GND_B55  = GND
  PETN12  = P5E_CPU0_G3_TX_C_DP<12>
  PETP12  = P5E_CPU0_G3_TX_C_DN<12>
  GND_B58  = GND
  PETN13  = P5E_CPU0_G3_TX_C_DP<13>
  PETP13  = P5E_CPU0_G3_TX_C_DN<13>
  GND_B61  = GND
  PETN14  = P5E_CPU0_G3_TX_C_DP<14>
  PETP14  = P5E_CPU0_G3_TX_C_DN<14>
  GND_B64  = GND
  PETN15  = P5E_CPU0_G3_TX_C_DP<15>
  PETP15  = P5E_CPU0_G3_TX_C_DN<15>
  GND_B67  = GND
  RFU1_NC_B68  = TP_OCP_SFF_B68
  RFU1_NC_B69  = TP_OCP_SFF_B69
  \prsntb3#\  = OCP_SFF_PRSNT3_R_N
  G1  = GND
  G2  = GND
  G3  = GND
  G4  = GND
  G5  = GND
  \perst2#\  = RST_PERST2_OCP_SFF_N
  \perst3#\  = RST_PERST3_OCP_SFF_N
  \wake#\  = IRQ_LVC3_OCP_SFF_WAKE_N
  RBT_ARB_IN  = OCP_SFF_ISO1_RBT_ARB_IN
  RBT_ARB_OUT  = OCP_SFF_ISO2_RBT_ARB_OUT
  SLOT_ID1  = OCP_SFF_ID1
  RBT_TX_EN  = NCSI_OCP_SFF_TX_EN
  RBT_TXD1  = NCSI_OCP_SFF_TXD1
  RBT_TXD0  = NCSI_OCP_SFF_TXD0
  GND_OA10  = GND
  REFCLKN3  = CLK_100M_CPU0_CLK05_DN
  REFCLKP3  = CLK_100M_CPU0_CLK05_DP
  GND_OA13  = GND
  RBT_CLK_IN  = CLK_50M_NCSI_OCP_SFF_ISO
  NIC_PWR_GOOD  = FM_OCP_SFF_PWR_GOOD
  MAIN_PWR_EN  = OCP_SFF_MAIN_PWR_EN_R
  \ld#\  = SGPIO_OCP_SFF_LD_N
  DATA_IN  = SGPIO_OCP_SFF_DATAIN
  DATA_OUT  = SGPIO_OCP_SFF_DATAOUT
  CLK  = SGPIO_OCP_SFF_CLK
  SLOT_ID0  = OCP_SFF_ID0
  RBT_RXD1  = NCSI_OCP_SFF_RXD1
  RBT_RXD0  = NCSI_OCP_SFF_RXD0
  GND_OB10  = GND
  REFCLKN2  = CLK_100M_CPU0_CLK04_DN
  REFCLKP2  = CLK_100M_CPU0_CLK04_DP
  GND_OB13  = GND
  RBT_CRS_DV  = NCSI_OCP_SFF_CRS_DV

(kicad_pcb
	(version 20260206)
	(generator "pcbnew")
	(generator_version "10.0")
	(general
		(thickness 1.6)
		(legacy_teardrops no)
	)
	(paper "A4")
	(title_block
		(title "04192023_DAF0TMB3IC0_F0TG_MB_C_brd_V02_OCP.brd")
		(comment 1 "Grand Teton / footprint 2929 of 8354 (J38), pads 1-45 of 175")
	)
	(layers
		(0 "F.Cu" signal "TOP")
		(4 "In1.Cu" signal "GND")
		(6 "In2.Cu" signal "IN1")
		(8 "In3.Cu" signal "GND1")
		(10 "In4.Cu" signal "IN2")
		(12 "In5.Cu" signal "GND2")
		(14 "In6.Cu" signal "IN3")
		(16 "In7.Cu" signal "GND3")
		(18 "In8.Cu" signal "VCC")
		(20 "In9.Cu" signal "VCC1")
		(22 "In10.Cu" signal "GND4")
		(24 "In11.Cu" signal "IN4")
		(26 "In12.Cu" signal "GND5")
		(28 "In13.Cu" signal "IN5")
		(30 "In14.Cu" signal "GND6")
		(32 "In15.Cu" signal "IN6")
		(34 "In16.Cu" signal "GND7")
		(2 "B.Cu" signal "BOTTOM")
		(9 "F.Adhes" user "F.Adhesive")
		(11 "B.Adhes" user "B.Adhesive")
		(13 "F.Paste" user "Package Geometry/Pastemask Top")
		(15 "B.Paste" user "Package Geometry/Pastemask Bottom")
		(5 "F.SilkS" user "Ref Des/Silkscreen Top")
		(7 "B.SilkS" user "Ref Des/Silkscreen Bottom")
		(1 "F.Mask" user "Board Geometry/Soldermask Top")
		(3 "B.Mask" user "Board Geometry/Soldermask Bottom")
		(17 "Dwgs.User" user "User.Drawings")
		(19 "Cmts.User" user "User.Comments")
		(21 "Eco1.User" user "User.Eco1")
		(23 "Eco2.User" user "User.Eco2")
		(25 "Edge.Cuts" user "Board Geometry/Outline")
		(27 "Margin" user)
		(31 "F.CrtYd" user "Package Geometry/Place Bound Top")
		(29 "B.CrtYd" user "Package Geometry/Place Bound Bottom")
		(35 "F.Fab" user "Ref Des/Assembly Top")
		(33 "B.Fab" user "Ref Des/Assembly Bottom")
	)
	(footprint ""
		(layer "F.Cu")
		(at 421.901874 -5.569966 -90)
		(property "Reference" "J38"
			(at -8.103616 -20.50034 0)
			(unlocked yes)
			(layer "F.SilkS")
			(effects
				(font
					(size 0.7874 0.5842)
					(thickness 0.1524)
				)
				(justify left)
			)
		)
		(property "Value" ""
			(at 0 0 270)
			(layer "F.Fab")
			(effects
				(font
					(size 1.27 1.27)
				)
			)
		)
		(duplicate_pad_numbers_are_jumpers no)
		(pad "" np_thru_hole circle
			(at -0.599948 -32.079946 180)
			(size 1.1176 1.1176)
			(drill 1.1176)
			(layers "*.Cu" "*.Mask")
			(clearance 0.381)
			(thermal_gap 0.381)
		)
		(pad "" np_thru_hole circle
			(at 0.40005 32.085026 180)
			(size 1.1176 1.1176)
			(drill 1.1176)
			(layers "*.Cu" "*.Mask")
			(clearance 0.381)
			(thermal_gap 0.381)
		)
		(pad "A1" smd rect
			(at -2.750058 -18.465038 180)
			(size 0.381 1.4478)
			(layers "F.Cu" "F.Mask" "F.Paste")
			(net "GND")
		)
		(pad "A2" smd rect
			(at -2.750058 -17.86509 180)
			(size 0.381 1.4478)
			(layers "F.Cu" "F.Mask" "F.Paste")
			(net "GND")
		)
		(pad "A3" smd rect
			(at -2.750058 -17.264888 180)
			(size 0.381 1.4478)
			(layers "F.Cu" "F.Mask" "F.Paste")
			(net "GND")
		)
		(pad "A4" smd rect
			(at -2.750058 -16.66494 180)
			(size 0.381 1.4478)
			(layers "F.Cu" "F.Mask" "F.Paste")
			(net "GND")
		)
		(pad "A5" smd rect
			(at -2.750058 -16.064992 180)
			(size 0.381 1.4478)
			(layers "F.Cu" "F.Mask" "F.Paste")
			(net "GND")
		)
		(pad "A6" smd rect
			(at -2.750058 -15.465044 180)
			(size 0.381 1.4478)
			(layers "F.Cu" "F.Mask" "F.Paste")
			(net "GND")
		)
		(pad "A7" smd rect
			(at -2.750058 -14.865096 180)
			(size 0.381 1.4478)
			(layers "F.Cu" "F.Mask" "F.Paste")
			(net "SMB_OCP_SFF_3V3AUX_BUF_R_SCL")
		)
		(pad "A8" smd rect
			(at -2.750058 -14.264894 180)
			(size 0.381 1.4478)
			(layers "F.Cu" "F.Mask" "F.Paste")
			(net "SMB_OCP_SFF_3V3AUX_BUF_R_SDA")
		)
		(pad "A9" smd rect
			(at -2.750058 -13.664946 180)
			(size 0.381 1.4478)
			(layers "F.Cu" "F.Mask" "F.Paste")
			(net "RST_SMB_OCP_SFF_N")
		)
		(pad "A10" smd rect
			(at -2.750058 -13.064998 180)
			(size 0.381 1.4478)
			(layers "F.Cu" "F.Mask" "F.Paste")
			(net "OCP_SFF_PRSNTA_R_N")
		)
		(pad "A11" smd rect
			(at -2.750058 -12.46505 180)
			(size 0.381 1.4478)
			(layers "F.Cu" "F.Mask" "F.Paste")
			(net "RST_PERST1_OCP_SFF_N")
		)
		(pad "A12" smd rect
			(at -2.750058 -11.865102 180)
			(size 0.381 1.4478)
			(layers "F.Cu" "F.Mask" "F.Paste")
			(net "OCP_SFF_PRSNT2_R_N")
		)
		(pad "A13" smd rect
			(at -2.750058 -11.2649 180)
			(size 0.381 1.4478)
			(layers "F.Cu" "F.Mask" "F.Paste")
			(net "GND")
		)
		(pad "A14" smd rect
			(at -2.750058 -10.664952 180)
			(size 0.381 1.4478)
			(layers "F.Cu" "F.Mask" "F.Paste")
			(net "CLK_100M_CPU0_CLK03_DN")
		)
		(pad "A15" smd rect
			(at -2.750058 -10.065004 180)
			(size 0.381 1.4478)
			(layers "F.Cu" "F.Mask" "F.Paste")
			(net "CLK_100M_CPU0_CLK03_DP")
		)
		(pad "A16" smd rect
			(at -2.750058 -9.465056 180)
			(size 0.381 1.4478)
			(layers "F.Cu" "F.Mask" "F.Paste")
			(net "GND")
		)
		(pad "A17" smd rect
			(at -2.750058 -8.865108 180)
			(size 0.381 1.4478)
			(layers "F.Cu" "F.Mask" "F.Paste")
			(net "P5E_CPU0_G3_RX_DN<0>")
		)
		(pad "A18" smd rect
			(at -2.750058 -8.264906 180)
			(size 0.381 1.4478)
			(layers "F.Cu" "F.Mask" "F.Paste")
			(net "P5E_CPU0_G3_RX_DP<0>")
		)
		(pad "A19" smd rect
			(at -2.750058 -7.664958 180)
			(size 0.381 1.4478)
			(layers "F.Cu" "F.Mask" "F.Paste")
			(net "GND")
		)
		(pad "A20" smd rect
			(at -2.750058 -7.06501 180)
			(size 0.381 1.4478)
			(layers "F.Cu" "F.Mask" "F.Paste")
			(net "P5E_CPU0_G3_RX_DN<1>")
		)
		(pad "A21" smd rect
			(at -2.750058 -6.465062 180)
			(size 0.381 1.4478)
			(layers "F.Cu" "F.Mask" "F.Paste")
			(net "P5E_CPU0_G3_RX_DP<1>")
		)
		(pad "A22" smd rect
			(at -2.750058 -5.865114 180)
			(size 0.381 1.4478)
			(layers "F.Cu" "F.Mask" "F.Paste")
			(net "GND")
		)
		(pad "A23" smd rect
			(at -2.750058 -5.264912 180)
			(size 0.381 1.4478)
			(layers "F.Cu" "F.Mask" "F.Paste")
			(net "P5E_CPU0_G3_RX_DN<2>")
		)
		(pad "A24" smd rect
			(at -2.750058 -4.664964 180)
			(size 0.381 1.4478)
			(layers "F.Cu" "F.Mask" "F.Paste")
			(net "P5E_CPU0_G3_RX_DP<2>")
		)
		(pad "A25" smd rect
			(at -2.750058 -4.065016 180)
			(size 0.381 1.4478)
			(layers "F.Cu" "F.Mask" "F.Paste")
			(net "GND")
		)
		(pad "A26" smd rect
			(at -2.750058 -3.465068 180)
			(size 0.381 1.4478)
			(layers "F.Cu" "F.Mask" "F.Paste")
			(net "P5E_CPU0_G3_RX_DN<3>")
		)
		(pad "A27" smd rect
			(at -2.750058 -2.86512 180)
			(size 0.381 1.4478)
			(layers "F.Cu" "F.Mask" "F.Paste")
			(net "P5E_CPU0_G3_RX_DP<3>")
		)
		(pad "A28" smd rect
			(at -2.750058 -2.264918 180)
			(size 0.381 1.4478)
			(layers "F.Cu" "F.Mask" "F.Paste")
			(net "GND")
		)
		(pad "A29" smd rect
			(at -2.750058 1.74498 180)
			(size 0.381 1.4478)
			(layers "F.Cu" "F.Mask" "F.Paste")
			(net "GND")
		)
		(pad "A30" smd rect
			(at -2.750058 2.344928 180)
			(size 0.381 1.4478)
			(layers "F.Cu" "F.Mask" "F.Paste")
			(net "P5E_CPU0_G3_RX_DN<4>")
		)
		(pad "A31" smd rect
			(at -2.750058 2.944876 180)
			(size 0.381 1.4478)
			(layers "F.Cu" "F.Mask" "F.Paste")
			(net "P5E_CPU0_G3_RX_DP<4>")
		)
		(pad "A32" smd rect
			(at -2.750058 3.545078 180)
			(size 0.381 1.4478)
			(layers "F.Cu" "F.Mask" "F.Paste")
			(net "GND")
		)
		(pad "A33" smd rect
			(at -2.750058 4.145026 180)
			(size 0.381 1.4478)
			(layers "F.Cu" "F.Mask" "F.Paste")
			(net "P5E_CPU0_G3_RX_DN<5>")
		)
		(pad "A34" smd rect
			(at -2.750058 4.744974 180)
			(size 0.381 1.4478)
			(layers "F.Cu" "F.Mask" "F.Paste")
			(net "P5E_CPU0_G3_RX_DP<5>")
		)
		(pad "A35" smd rect
			(at -2.750058 5.344922 180)
			(size 0.381 1.4478)
			(layers "F.Cu" "F.Mask" "F.Paste")
			(net "GND")
		)
		(pad "A36" smd rect
			(at -2.750058 5.945124 180)
			(size 0.381 1.4478)
			(layers "F.Cu" "F.Mask" "F.Paste")
			(net "P5E_CPU0_G3_RX_DN<6>")
		)
		(pad "A37" smd rect
			(at -2.750058 6.545072 180)
			(size 0.381 1.4478)
			(layers "F.Cu" "F.Mask" "F.Paste")
			(net "P5E_CPU0_G3_RX_DP<6>")
		)
		(pad "A38" smd rect
			(at -2.750058 7.14502 180)
			(size 0.381 1.4478)
			(layers "F.Cu" "F.Mask" "F.Paste")
			(net "GND")
		)
		(pad "A39" smd rect
			(at -2.750058 7.744968 180)
			(size 0.381 1.4478)
			(layers "F.Cu" "F.Mask" "F.Paste")
			(net "P5E_CPU0_G3_RX_DN<7>")
		)
		(pad "A40" smd rect
			(at -2.750058 8.344916 180)
			(size 0.381 1.4478)
			(layers "F.Cu" "F.Mask" "F.Paste")
			(net "P5E_CPU0_G3_RX_DP<7>")
		)
		(pad "A41" smd rect
			(at -2.750058 8.945118 180)
			(size 0.381 1.4478)
			(layers "F.Cu" "F.Mask" "F.Paste")
			(net "GND")
		)
		(pad "A42" smd rect
			(at -2.750058 9.545066 180)
			(size 0.381 1.4478)
			(layers "F.Cu" "F.Mask" "F.Paste")
			(net "OCP_SFF_PRSNT1_R_N")
		)
		(pad "A43" smd rect
			(at -2.750058 14.454886 180)
			(size 0.381 1.4478)
			(layers "F.Cu" "F.Mask" "F.Paste")
			(net "GND")
		)
	)
)
